# T6G (Grand Teton) — schematic netlist excerpt (pin names and nets, part order shuffled) for the footprints in the layout excerpt that follows; sources: Cadence DE-HDL packaged netlist, KiCad conversion of 04192023_DAF0TMB3IC0_F0TG_MB_C_brd_V02_OCP.brd

R4179  Q_RES  33.2 1% CHIP  pkg 0402LF  page 235 : A = SMB_LM75_1_3V3AUX_SCL ; B = SMB_LM75_1_3V3AUX_SCL_R1
R6809  Q_RES  200 1% CHIP  pkg 0201LF  page 277 : A = RT_CPU0_P0_VQPS ; B = GND
R8023  Q_RES  560 1% CHIP  pkg 0402LF  page 256 : A = LED_P12V_AUX_R2 ; B = LED_P12V_AUX_R3

(kicad_pcb
	(version 20260206)
	(generator "pcbnew")
	(generator_version "10.0")
	(general
		(thickness 1.6)
		(legacy_teardrops no)
	)
	(paper "A4")
	(title_block
		(title "04192023_DAF0TMB3IC0_F0TG_MB_C_brd_V02_OCP.brd")
		(comment 1 "Grand Teton / footprints 3769-3771 of 8354")
	)
	(layers
		(0 "F.Cu" signal "TOP")
		(4 "In1.Cu" signal "GND")
		(6 "In2.Cu" signal "IN1")
		(8 "In3.Cu" signal "GND1")
		(10 "In4.Cu" signal "IN2")
		(12 "In5.Cu" signal "GND2")
		(14 "In6.Cu" signal "IN3")
		(16 "In7.Cu" signal "GND3")
		(18 "In8.Cu" signal "VCC")
		(20 "In9.Cu" signal "VCC1")
		(22 "In10.Cu" signal "GND4")
		(24 "In11.Cu" signal "IN4")
		(26 "In12.Cu" signal "GND5")
		(28 "In13.Cu" signal "IN5")
		(30 "In14.Cu" signal "GND6")
		(32 "In15.Cu" signal "IN6")
		(34 "In16.Cu" signal "GND7")
		(2 "B.Cu" signal "BOTTOM")
		(9 "F.Adhes" user "F.Adhesive")
		(11 "B.Adhes" user "B.Adhesive")
		(13 "F.Paste" user "Package Geometry/Pastemask Top")
		(15 "B.Paste" user "Package Geometry/Pastemask Bottom")
		(5 "F.SilkS" user "Ref Des/Silkscreen Top")
		(7 "B.SilkS" user "Ref Des/Silkscreen Bottom")
		(1 "F.Mask" user "Board Geometry/Soldermask Top")
		(3 "B.Mask" user "Board Geometry/Soldermask Bottom")
		(17 "Dwgs.User" user "User.Drawings")
		(19 "Cmts.User" user "User.Comments")
		(21 "Eco1.User" user "User.Eco1")
		(23 "Eco2.User" user "User.Eco2")
		(25 "Edge.Cuts" user "Board Geometry/Outline")
		(27 "Margin" user)
		(31 "F.CrtYd" user "Package Geometry/Place Bound Top")
		(29 "B.CrtYd" user "Package Geometry/Place Bound Bottom")
		(35 "F.Fab" user "Ref Des/Assembly Top")
		(33 "B.Fab" user "Ref Des/Assembly Bottom")
	)
	(footprint ""
		(layer "F.Cu")
		(at 320.612262 -403.1615 -90)
		(property "Reference" "R6809"
			(at 0 0 270)
			(layer "F.SilkS")
			(hide yes)
			(effects
				(font
					(size 1.27 1.27)
				)
			)
		)
		(property "Value" ""
			(at 0 0 270)
			(layer "F.Fab")
			(effects
				(font
					(size 1.27 1.27)
				)
			)
		)
		(duplicate_pad_numbers_are_jumpers no)
		(fp_line
			(start -0.32512 0.175006)
			(end -0.32512 -0.175006)
			(stroke
				(width 0.1)
				(type default)
			)
			(layer "F.Fab")
		)
		(fp_line
			(start 0.32512 0.175006)
			(end -0.32512 0.175006)
			(stroke
				(width 0.1)
				(type default)
			)
			(layer "F.Fab")
		)
		(fp_line
			(start -0.32512 -0.175006)
			(end 0.32512 -0.175006)
			(stroke
				(width 0.1)
				(type default)
			)
			(layer "F.Fab")
		)
		(fp_line
			(start 0.32512 -0.175006)
			(end 0.32512 0.175006)
			(stroke
				(width 0.1)
				(type default)
			)
			(layer "F.Fab")
		)
		(pad "1" smd rect
			(at -0.2667 0 270)
			(size 0.3048 0.381)
			(layers "F.Cu" "F.Mask" "F.Paste")
			(net "RT_CPU0_P0_VQPS")
		)
		(pad "2" smd rect
			(at 0.2667 0 90)
			(size 0.3048 0.381)
			(layers "F.Cu" "F.Mask" "F.Paste")
			(net "GND")
		)
	)
	(footprint ""
		(layer "F.Cu")
		(at 367.441226 -62.0903)
		(property "Reference" "R8023"
			(at 0 0 0)
			(layer "F.SilkS")
			(hide yes)
			(effects
				(font
					(size 1.27 1.27)
				)
			)
		)
		(property "Value" ""
			(at 0 0 0)
			(layer "F.Fab")
			(effects
				(font
					(size 1.27 1.27)
				)
			)
		)
		(duplicate_pad_numbers_are_jumpers no)
		(fp_line
			(start -0.7874 -0.4064)
			(end 0.7874 -0.4064)
			(stroke
				(width 0.1524)
				(type default)
			)
			(layer "F.SilkS")
		)
		(fp_line
			(start -0.7874 0.4064)
			(end -0.7874 -0.4064)
			(stroke
				(width 0.1524)
				(type default)
			)
			(layer "F.SilkS")
		)
		(fp_line
			(start 0.7874 -0.4064)
			(end 0.7874 0.4064)
			(stroke
				(width 0.1524)
				(type default)
			)
			(layer "F.SilkS")
		)
		(fp_line
			(start 0.7874 0.4064)
			(end -0.7874 0.4064)
			(stroke
				(width 0.1524)
				(type default)
			)
			(layer "F.SilkS")
		)
		(fp_line
			(start -0.67945 -0.305054)
			(end -0.12065 -0.305054)
			(stroke
				(width 0.1)
				(type default)
			)
			(layer "F.Fab")
		)
		(fp_line
			(start -0.67945 0.3048)
			(end -0.67945 -0.305054)
			(stroke
				(width 0.1)
				(type default)
			)
			(layer "F.Fab")
		)
		(fp_line
			(start -0.12065 -0.305054)
			(end -0.12065 -0.2794)
			(stroke
				(width 0.1)
				(type default)
			)
			(layer "F.Fab")
		)
		(fp_line
			(start -0.12065 -0.2794)
			(end 0.12065 -0.2794)
			(stroke
				(width 0.1)
				(type default)
			)
			(layer "F.Fab")
		)
		(fp_line
			(start -0.12065 0.2794)
			(end -0.12065 0.3048)
			(stroke
				(width 0.1)
				(type default)
			)
			(layer "F.Fab")
		)
		(fp_line
			(start -0.12065 0.3048)
			(end -0.67945 0.3048)
			(stroke
				(width 0.1)
				(type default)
			)
			(layer "F.Fab")
		)
		(fp_line
			(start 0.120396 0.2794)
			(end -0.12065 0.2794)
			(stroke
				(width 0.1)
				(type default)
			)
			(layer "F.Fab")
		)
		(fp_line
			(start 0.120396 0.3048)
			(end 0.120396 0.2794)
			(stroke
				(width 0.1)
				(type default)
			)
			(layer "F.Fab")
		)
		(fp_line
			(start 0.12065 -0.3048)
			(end 0.67945 -0.3048)
			(stroke
				(width 0.1)
				(type default)
			)
			(layer "F.Fab")
		)
		(fp_line
			(start 0.12065 -0.2794)
			(end 0.12065 -0.3048)
			(stroke
				(width 0.1)
				(type default)
			)
			(layer "F.Fab")
		)
		(fp_line
			(start 0.67945 -0.3048)
			(end 0.67945 0.3048)
			(stroke
				(width 0.1)
				(type default)
			)
			(layer "F.Fab")
		)
		(fp_line
			(start 0.67945 0.3048)
			(end 0.120396 0.3048)
			(stroke
				(width 0.1)
				(type default)
			)
			(layer "F.Fab")
		)
		(pad "1" smd circle
			(at -0.40005 0)
			(size 0 0)
			(layers "F.Cu" "F.Mask" "F.Paste")
			(net "LED_P12V_AUX_R2")
		)
		(pad "2" smd circle
			(at 0.40005 0)
			(size 0 0)
			(layers "F.Cu" "F.Mask" "F.Paste")
			(net "LED_P12V_AUX_R3")
		)
	)
	(footprint ""
		(layer "F.Cu")
		(at 288.198052 -14.354048)
		(property "Reference" "R4179"
			(at 0 0 0)
			(layer "F.SilkS")
			(hide yes)
			(effects
				(font
					(size 1.27 1.27)
				)
			)
		)
		(property "Value" ""
			(at 0 0 0)
			(layer "F.Fab")
			(effects
				(font
					(size 1.27 1.27)
				)
			)
		)
		(duplicate_pad_numbers_are_jumpers no)
		(fp_line
			(start -0.7874 -0.4064)
			(end 0.7874 -0.4064)
			(stroke
				(width 0.1524)
				(type default)
			)
			(layer "F.SilkS")
		)
		(fp_line
			(start -0.7874 0.4064)
			(end -0.7874 -0.4064)
			(stroke
				(width 0.1524)
				(type default)
			)
			(layer "F.SilkS")
		)
		(fp_line
			(start 0.7874 -0.4064)
			(end 0.7874 0.4064)
			(stroke
				(width 0.1524)
				(type default)
			)
			(layer "F.SilkS")
		)
		(fp_line
			(start 0.7874 0.4064)
			(end -0.7874 0.4064)
			(stroke
				(width 0.1524)
				(type default)
			)
			(layer "F.SilkS")
		)
		(fp_line
			(start -0.67945 -0.305054)
			(end -0.12065 -0.305054)
			(stroke
				(width 0.1)
				(type default)
			)
			(layer "F.Fab")
		)
		(fp_line
			(start -0.67945 0.3048)
			(end -0.67945 -0.305054)
			(stroke
				(width 0.1)
				(type default)
			)
			(layer "F.Fab")
		)
		(fp_line
			(start -0.12065 -0.305054)
			(end -0.12065 -0.2794)
			(stroke
				(width 0.1)
				(type default)
			)
			(layer "F.Fab")
		)
		(fp_line
			(start -0.12065 -0.2794)
			(end 0.12065 -0.2794)
			(stroke
				(width 0.1)
				(type default)
			)
			(layer "F.Fab")
		)
		(fp_line
			(start -0.12065 0.2794)
			(end -0.12065 0.3048)
			(stroke
				(width 0.1)
				(type default)
			)
			(layer "F.Fab")
		)
		(fp_line
			(start -0.12065 0.3048)
			(end -0.67945 0.3048)
			(stroke
				(width 0.1)
				(type default)
			)
			(layer "F.Fab")
		)
		(fp_line
			(start 0.120396 0.2794)
			(end -0.12065 0.2794)
			(stroke
				(width 0.1)
				(type default)
			)
			(layer "F.Fab")
		)
		(fp_line
			(start 0.120396 0.3048)
			(end 0.120396 0.2794)
			(stroke
				(width 0.1)
				(type default)
			)
			(layer "F.Fab")
		)
		(fp_line
			(start 0.12065 -0.3048)
			(end 0.67945 -0.3048)
			(stroke
				(width 0.1)
				(type default)
			)
			(layer "F.Fab")
		)
		(fp_line
			(start 0.12065 -0.2794)
			(end 0.12065 -0.3048)
			(stroke
				(width 0.1)
				(type default)
			)
			(layer "F.Fab")
		)
		(fp_line
			(start 0.67945 -0.3048)
			(end 0.67945 0.3048)
			(stroke
				(width 0.1)
				(type default)
			)
			(layer "F.Fab")
		)
		(fp_line
			(start 0.67945 0.3048)
			(end 0.120396 0.3048)
			(stroke
				(width 0.1)
				(type default)
			)
			(layer "F.Fab")
		)
		(pad "1" smd circle
			(at -0.40005 0)
			(size 0 0)
			(layers "F.Cu" "F.Mask" "F.Paste")
			(net "SMB_LM75_1_3V3AUX_SCL")
		)
		(pad "2" smd circle
			(at 0.40005 0)
			(size 0 0)
			(layers "F.Cu" "F.Mask" "F.Paste")
			(net "SMB_LM75_1_3V3AUX_SCL_R1")
		)
	)
)
